#ISCELL
  mstr_misc dns *
  *
#ISCELL
  pure_quanta quanta_title_block_c *
  *
#CELL
  pure_quanta q_cap *
  page178_i100
#CELL
  pure_quanta q_cap *
  page178_i101
#ISCELL
  pure_quanta_power universal_gnd *
  page178_i102
#CELL
  pure_quanta q_cap *
  page178_i103
#CELL
  pure_quanta q_cap *
  page178_i105
#CELL
  pure_quanta q_cap *
  page178_i106
#CELL
  pure_quanta q_cap *
  page178_i107
#CELL
  pure_quanta q_res *
  page178_i108
#ISCELL
  pure_quanta_power universal_gnd *
  page178_i109
#CELL
  pure_quanta q_res *
  page178_i110
#CELL
  pure_quanta q_cap *
  page178_i111
#ISCELL
  pure_quanta_power universal_gnd *
  page178_i112
#CELL
  pure_quanta q_res *
  page178_i114
#CELL
  pure_quanta q_cap *
  page178_i115
#ISCELL
  pure_quanta_power universal_gnd *
  page178_i116
#ISCELL
  standard offpage *
  page178_i117
#ISCELL
  standard offpage *
  page178_i118
#ISCELL
  pure_quanta_power universal_gnd *
  page178_i119
#CELL
  pure_quanta isl99390frztr5935 *
  page178_i120
#ISCELL
  standard offpage *
  page178_i121
#ISCELL
  standard offpage *
  page178_i122
#CELL
  pure_quanta q_res *
  page178_i123
#ISCELL
  pure_quanta_power universal_gnd *
  page178_i124
#CELL
  pure_quanta q_cap *
  page178_i125
#ISCELL
  pure_quanta_power universal_gnd *
  page178_i126
#ISCELL
  pure_quanta_power universal_gnd *
  page178_i127
#CELL
  pure_quanta q_res *
  page178_i128
#CELL
  pure_quanta q_cap *
  page178_i129
#ISCELL
  pure_quanta_power universal_gnd *
  page178_i130
#CELL
  pure_quanta q_res *
  page178_i131
#CELL
  pure_quanta q_cap *
  page178_i132
#ISCELL
  pure_quanta_power vcc_core *
  page178_i133
#ISCELL
  pure_quanta_power vcc_core *
  page178_i134
#ISCELL
  pure_quanta_power universal_gnd *
  page178_i135
#CELL
  pure_quanta q_inductor *
  page178_i136
#ISCELL
  pure_quanta_power universal_gnd *
  page178_i20
#CELL
  pure_quanta q_res *
  page178_i21
#ISCELL
  standard offpage *
  page178_i23
#ISCELL
  standard offpage *
  page178_i25
#ISCELL
  standard offpage *
  page178_i26
#ISCELL
  standard offpage *
  page178_i28
#CELL
  pure_quanta isl99390frztr5935 *
  page178_i31
#ISCELL
  pure_quanta_power universal_gnd *
  page178_i36
#CELL
  pure_quanta q_cap *
  page178_i39
#CELL
  pure_quanta q_cap *
  page178_i40
#ISCELL
  pure_quanta_power universal_gnd *
  page178_i54
#CELL
  pure_quanta q_cap *
  page178_i59
#CELL
  pure_quanta q_cap *
  page178_i60
#ISCELL
  pure_quanta_power vcc_core *
  page178_i61
#ISCELL
  standard offpage *
  page178_i73
#ISCELL
  standard offpage *
  page178_i75
#CELL
  pure_quanta q_res *
  page178_i76
#ISCELL
  pure_quanta_power vcc_core *
  page178_i77
#ISCELL
  pure_quanta_power universal_gnd *
  page178_i78
#CELL
  pure_quanta q_cap *
  page178_i79
#CELL
  pure_quanta q_cap *
  page178_i80
#CELL
  pure_quanta q_inductor4p_14 *
  page178_i82
#CELL
  pure_quanta q_cap *
  page178_i83
#CELL
  pure_quanta q_cap *
  page178_i84
#CELL
  pure_quanta q_res *
  page178_i85
#CELL
  pure_quanta q_cap *
  page178_i86
#CELL
  pure_quanta q_cap *
  page178_i87
#ISCELL
  pure_quanta_power universal_gnd *
  page178_i88
#ISCELL
  pure_quanta_power universal_gnd *
  page178_i89
#CELL
  pure_quanta q_res *
  page178_i90
#CELL
  pure_quanta q_cap *
  page178_i91
#ISCELL
  pure_quanta_power universal_gnd *
  page178_i93
#CELL
  pure_quanta q_inductor4p_14 *
  page178_i94
#ISCELL
  pure_quanta_power vcc_core *
  page178_i95
#CELL
  pure_quanta q_cap *
  page178_i96
#CELL
  pure_quanta q_cap *
  page178_i97
#ISCELL
  standard offpage *
  page178_i98
#ISCELL
  pure_quanta_power vcc_core *
  page178_i99
